(kicad_pcb
	(version 20260206)
	(generator "pcbnew")
	(generator_version "10.0")
	(general
		(thickness 1.6)
		(legacy_teardrops no)
	)
	(paper "A4")
	(title_block
		(title "04192023_DAF0TMB3IC0_F0TG_MB_C_brd_V02_OCP.brd")
		(comment 1 "Grand Teton / footprints 6076-6081 of 8354")
	)
	(layers
		(0 "F.Cu" signal "TOP")
		(4 "In1.Cu" signal "GND")
		(6 "In2.Cu" signal "IN1")
		(8 "In3.Cu" signal "GND1")
		(10 "In4.Cu" signal "IN2")
		(12 "In5.Cu" signal "GND2")
		(14 "In6.Cu" signal "IN3")
		(16 "In7.Cu" signal "GND3")
		(18 "In8.Cu" signal "VCC")
		(20 "In9.Cu" signal "VCC1")
		(22 "In10.Cu" signal "GND4")
		(24 "In11.Cu" signal "IN4")
		(26 "In12.Cu" signal "GND5")
		(28 "In13.Cu" signal "IN5")
		(30 "In14.Cu" signal "GND6")
		(32 "In15.Cu" signal "IN6")
		(34 "In16.Cu" signal "GND7")
		(2 "B.Cu" signal "BOTTOM")
		(9 "F.Adhes" user "F.Adhesive")
		(11 "B.Adhes" user "B.Adhesive")
		(13 "F.Paste" user "Package Geometry/Pastemask Top")
		(15 "B.Paste" user "Package Geometry/Pastemask Bottom")
		(5 "F.SilkS" user "Ref Des/Silkscreen Top")
		(7 "B.SilkS" user "Ref Des/Silkscreen Bottom")
		(1 "F.Mask" user "Board Geometry/Soldermask Top")
		(3 "B.Mask" user "Board Geometry/Soldermask Bottom")
		(17 "Dwgs.User" user "User.Drawings")
		(19 "Cmts.User" user "User.Comments")
		(21 "Eco1.User" user "User.Eco1")
		(23 "Eco2.User" user "User.Eco2")
		(25 "Edge.Cuts" user "Board Geometry/Outline")
		(27 "Margin" user)
		(31 "F.CrtYd" user "Package Geometry/Place Bound Top")
		(29 "B.CrtYd" user "Package Geometry/Place Bound Bottom")
		(35 "F.Fab" user "Ref Des/Assembly Top")
		(33 "B.Fab" user "Ref Des/Assembly Bottom")
	)
	(footprint ""
		(layer "B.Cu")
		(at 255.744726 -323.022722 180)
		(property "Reference" "C1078"
			(at 0 0 0)
			(layer "B.SilkS")
			(hide yes)
			(effects
				(font
					(size 1.27 1.27)
				)
				(justify mirror)
			)
		)
		(property "Value" ""
			(at 0 0 0)
			(layer "B.Fab")
			(effects
				(font
					(size 1.27 1.27)
				)
				(justify mirror)
			)
		)
		(duplicate_pad_numbers_are_jumpers no)
		(fp_line
			(start 0.7874 0.4064)
			(end 0.7874 -0.4064)
			(stroke
				(width 0.1524)
				(type default)
			)
			(layer "B.SilkS")
		)
		(fp_line
			(start 0.7874 -0.4064)
			(end -0.7874 -0.4064)
			(stroke
				(width 0.1524)
				(type default)
			)
			(layer "B.SilkS")
		)
		(fp_line
			(start -0.7874 0.4064)
			(end 0.7874 0.4064)
			(stroke
				(width 0.1524)
				(type default)
			)
			(layer "B.SilkS")
		)
		(fp_line
			(start -0.7874 -0.4064)
			(end -0.7874 0.4064)
			(stroke
				(width 0.1524)
				(type default)
			)
			(layer "B.SilkS")
		)
		(fp_line
			(start 0.67945 0.3048)
			(end 0.67945 -0.305054)
			(stroke
				(width 0.1)
				(type default)
			)
			(layer "B.Fab")
		)
		(fp_line
			(start 0.67945 -0.305054)
			(end 0.12065 -0.305054)
			(stroke
				(width 0.1)
				(type default)
			)
			(layer "B.Fab")
		)
		(fp_line
			(start 0.12065 0.3048)
			(end 0.67945 0.3048)
			(stroke
				(width 0.1)
				(type default)
			)
			(layer "B.Fab")
		)
		(fp_line
			(start 0.12065 0.2794)
			(end 0.12065 0.3048)
			(stroke
				(width 0.1)
				(type default)
			)
			(layer "B.Fab")
		)
		(fp_line
			(start 0.12065 -0.2794)
			(end -0.12065 -0.2794)
			(stroke
				(width 0.1)
				(type default)
			)
			(layer "B.Fab")
		)
		(fp_line
			(start 0.12065 -0.305054)
			(end 0.12065 -0.2794)
			(stroke
				(width 0.1)
				(type default)
			)
			(layer "B.Fab")
		)
		(fp_line
			(start -0.120396 0.3048)
			(end -0.120396 0.2794)
			(stroke
				(width 0.1)
				(type default)
			)
			(layer "B.Fab")
		)
		(fp_line
			(start -0.120396 0.2794)
			(end 0.12065 0.2794)
			(stroke
				(width 0.1)
				(type default)
			)
			(layer "B.Fab")
		)
		(fp_line
			(start -0.12065 -0.2794)
			(end -0.12065 -0.3048)
			(stroke
				(width 0.1)
				(type default)
			)
			(layer "B.Fab")
		)
		(fp_line
			(start -0.12065 -0.3048)
			(end -0.67945 -0.3048)
			(stroke
				(width 0.1)
				(type default)
			)
			(layer "B.Fab")
		)
		(fp_line
			(start -0.67945 0.3048)
			(end -0.120396 0.3048)
			(stroke
				(width 0.1)
				(type default)
			)
			(layer "B.Fab")
		)
		(fp_line
			(start -0.67945 -0.3048)
			(end -0.67945 0.3048)
			(stroke
				(width 0.1)
				(type default)
			)
			(layer "B.Fab")
		)
		(pad "1" smd circle
			(at 0.40005 0)
			(size 0 0)
			(layers "B.Cu" "B.Mask" "B.Paste")
			(net "P1V2_AUX_ADC_MAM")
		)
		(pad "2" smd circle
			(at -0.40005 0)
			(size 0 0)
			(layers "B.Cu" "B.Mask" "B.Paste")
			(net "GND")
		)
	)
	(footprint ""
		(layer "B.Cu")
		(at 493.36833 7.564882 90)
		(property "Reference" "X8026"
			(at 0.93726 -1.53035 270)
			(unlocked yes)
			(layer "B.SilkS")
			(effects
				(font
					(size 0.7874 0.5842)
					(thickness 0.1524)
				)
				(justify left mirror)
			)
		)
		(property "Value" ""
			(at 0 0 90)
			(layer "B.Fab")
			(effects
				(font
					(size 1.27 1.27)
				)
				(justify mirror)
			)
		)
		(property "Device Type" "TP_TDR_4P_FTS_TH-TP_TDR_4P_DIP,EMPTY,TP15"
			(at -1.30175 1.27 0)
			(unlocked yes)
			(layer "B.Fab")
			(hide yes)
			(effects
				(font
					(size 0.635 0.4064)
					(thickness 0.1524)
				)
				(justify mirror)
			)
		)
		(property "User Part Number" "N_A"
			(at -1.30175 1.27 0)
			(unlocked yes)
			(layer "Cmts.User")
			(hide yes)
			(effects
				(font
					(size 0.635 0.4064)
					(thickness 0.1524)
				)
				(justify mirror)
			)
		)
		(duplicate_pad_numbers_are_jumpers no)
		(fp_line
			(start 0 -1.27)
			(end 0 -0.635)
			(stroke
				(width 0.1524)
				(type default)
			)
			(layer "B.SilkS")
		)
		(fp_line
			(start -2.54 -1.27)
			(end 0 -1.27)
			(stroke
				(width 0.1524)
				(type default)
			)
			(layer "B.SilkS")
		)
		(fp_line
			(start -2.54 -1.1303)
			(end -2.54 -1.27)
			(stroke
				(width 0.1524)
				(type default)
			)
			(layer "B.SilkS")
		)
		(fp_line
			(start 0 0.635)
			(end 0 1.905)
			(stroke
				(width 0.1524)
				(type default)
			)
			(layer "B.SilkS")
		)
		(fp_line
			(start -2.54 1.4097)
			(end -2.54 1.1303)
			(stroke
				(width 0.1524)
				(type default)
			)
			(layer "B.SilkS")
		)
		(fp_line
			(start 0 3.175)
			(end 0 3.81)
			(stroke
				(width 0.1524)
				(type default)
			)
			(layer "B.SilkS")
		)
		(fp_line
			(start 0 3.81)
			(end -2.54 3.81)
			(stroke
				(width 0.1524)
				(type default)
			)
			(layer "B.SilkS")
		)
		(fp_line
			(start -2.54 3.81)
			(end -2.54 3.6703)
			(stroke
				(width 0.1524)
				(type default)
			)
			(layer "B.SilkS")
		)
		(fp_poly
			(pts
				(xy 0.761746 0) (xy 2.285746 -0.762) (xy 2.285746 0.762)
			)
			(stroke
				(width 0)
				(type default)
			)
			(fill yes)
			(layer "B.SilkS")
		)
		(fp_line
			(start 0 -1.27)
			(end 0 3.81)
			(stroke
				(width 0.1)
				(type default)
			)
			(layer "B.Fab")
		)
		(fp_line
			(start -2.54 -1.27)
			(end 0 -1.27)
			(stroke
				(width 0.1)
				(type default)
			)
			(layer "B.Fab")
		)
		(fp_line
			(start 0 3.81)
			(end -2.54 3.81)
			(stroke
				(width 0.1)
				(type default)
			)
			(layer "B.Fab")
		)
		(fp_line
			(start -2.54 3.81)
			(end -2.54 -1.27)
			(stroke
				(width 0.1)
				(type default)
			)
			(layer "B.Fab")
		)
		(fp_poly
			(pts
				(xy 0.761746 0) (xy 2.285746 -0.762) (xy 2.285746 0.762)
			)
			(stroke
				(width 0)
				(type default)
			)
			(fill yes)
			(layer "B.Fab")
		)
		(pad "1" thru_hole circle
			(at 0 0 270)
			(size 1.0033 1.0033)
			(drill 0.249936)
			(layers "*.Cu" "*.Mask")
			(remove_unused_layers no)
			(net "TDR_DIFF_85_IN6_DP")
			(clearance 0.10795)
			(padstack
				(mode front_inner_back)
				(layer "Inner"
					(shape circle)
					(size 0.8001 0.8001)
					(clearance 0.1524)
				)
				(layer "B.Cu"
					(shape circle)
					(size 1.0033 1.0033)
					(thermal_gap 0.10795)
					(clearance 0.10795)
				)
			)
		)
		(pad "2" thru_hole circle
			(at -2.54 0 270)
			(size 1.9939 1.9939)
			(drill 0.249936)
			(layers "*.Cu" "*.Mask")
			(remove_unused_layers no)
			(net "T1_GND")
			(clearance 0.10795)
			(padstack
				(mode front_inner_back)
				(layer "Inner"
					(shape circle)
					(size 0.8001 0.8001)
					(clearance 0.1524)
				)
				(layer "B.Cu"
					(shape circle)
					(size 1.9939 1.9939)
					(thermal_gap 0.10795)
					(clearance 0.10795)
				)
			)
		)
		(pad "3" thru_hole circle
			(at -2.54 2.54 270)
			(size 1.9939 1.9939)
			(drill 0.249936)
			(layers "*.Cu" "*.Mask")
			(remove_unused_layers no)
			(net "T1_GND")
			(clearance 0.10795)
			(padstack
				(mode front_inner_back)
				(layer "Inner"
					(shape circle)
					(size 0.8001 0.8001)
					(clearance 0.1524)
				)
				(layer "B.Cu"
					(shape circle)
					(size 1.9939 1.9939)
					(thermal_gap 0.10795)
					(clearance 0.10795)
				)
			)
		)
		(pad "4" thru_hole circle
			(at 0 2.54 270)
			(size 1.0033 1.0033)
			(drill 0.249936)
			(layers "*.Cu" "*.Mask")
			(remove_unused_layers no)
			(net "TDR_DIFF_85_IN6_DN")
			(clearance 0.10795)
			(padstack
				(mode front_inner_back)
				(layer "Inner"
					(shape circle)
					(size 0.8001 0.8001)
					(clearance 0.1524)
				)
				(layer "B.Cu"
					(shape circle)
					(size 1.0033 1.0033)
					(thermal_gap 0.10795)
					(clearance 0.10795)
				)
			)
		)
	)
	(footprint ""
		(layer "B.Cu")
		(at 184.332372 -111.863124 -90)
		(property "Reference" "C1131"
			(at 0 0 90)
			(layer "B.SilkS")
			(hide yes)
			(effects
				(font
					(size 1.27 1.27)
				)
				(justify mirror)
			)
		)
		(property "Value" ""
			(at 0 0 90)
			(layer "B.Fab")
			(effects
				(font
					(size 1.27 1.27)
				)
				(justify mirror)
			)
		)
		(duplicate_pad_numbers_are_jumpers no)
		(fp_line
			(start -0.69215 0.2921)
			(end 0.69215 0.2921)
			(stroke
				(width 0.1524)
				(type default)
			)
			(layer "B.SilkS")
		)
		(fp_line
			(start 0.69215 0.2921)
			(end 0.69215 -0.2921)
			(stroke
				(width 0.1524)
				(type default)
			)
			(layer "B.SilkS")
		)
		(fp_line
			(start -0.69215 -0.2921)
			(end -0.69215 0.2921)
			(stroke
				(width 0.1524)
				(type default)
			)
			(layer "B.SilkS")
		)
		(fp_line
			(start 0.69215 -0.2921)
			(end -0.69215 -0.2921)
			(stroke
				(width 0.1524)
				(type default)
			)
			(layer "B.SilkS")
		)
		(fp_line
			(start -0.51435 0.2794)
			(end 0.51435 0.2794)
			(stroke
				(width 0.1)
				(type default)
			)
			(layer "B.Fab")
		)
		(fp_line
			(start 0.51435 0.2794)
			(end 0.51435 -0.2794)
			(stroke
				(width 0.1)
				(type default)
			)
			(layer "B.Fab")
		)
		(fp_line
			(start -0.51435 -0.2794)
			(end -0.51435 0.2794)
			(stroke
				(width 0.1)
				(type default)
			)
			(layer "B.Fab")
		)
		(fp_line
			(start 0.51435 -0.2794)
			(end -0.51435 -0.2794)
			(stroke
				(width 0.1)
				(type default)
			)
			(layer "B.Fab")
		)
		(pad "1" smd circle
			(at 0.40005 0 90)
			(size 0 0)
			(layers "B.Cu" "B.Mask" "B.Paste")
			(net "P1V8_AUX")
		)
		(pad "2" smd circle
			(at -0.40005 0 90)
			(size 0 0)
			(layers "B.Cu" "B.Mask" "B.Paste")
			(net "GND")
		)
		(zone
			(layer "B.Cu")
			(hatch none 0.5)
			(connect_pads
				(clearance 0)
			)
			(min_thickness 0.25)
			(keepout
				(tracks not_allowed)
				(vias allowed)
				(pads allowed)
				(copperpour not_allowed)
				(footprints allowed)
			)
			(placement
				(enabled no)
				(sheetname "")
			)
			(fill
				(thermal_gap 0.5)
				(thermal_bridge_width 0.5)
				(island_removal_mode 0)
			)
			(polygon
				(pts
					(xy 184.186576 -111.764064) (xy 184.186576 -111.963454) (xy 184.244742 -112.053624) (xy 184.420002 -112.053624)
					(xy 184.478422 -111.963454) (xy 184.478422 -111.764064) (xy 184.420256 -111.672624) (xy 184.244742 -111.672624)
				)
			)
		)
	)
	(footprint ""
		(layer "B.Cu")
		(at 259.565394 -51.213512 -90)
		(property "Reference" "PC2341"
			(at 0 0 90)
			(layer "B.SilkS")
			(hide yes)
			(effects
				(font
					(size 1.27 1.27)
				)
				(justify mirror)
			)
		)
		(property "Value" ""
			(at 0 0 90)
			(layer "B.Fab")
			(effects
				(font
					(size 1.27 1.27)
				)
				(justify mirror)
			)
		)
		(duplicate_pad_numbers_are_jumpers no)
		(fp_line
			(start -0.7874 0.4064)
			(end 0.7874 0.4064)
			(stroke
				(width 0.1524)
				(type default)
			)
			(layer "B.SilkS")
		)
		(fp_line
			(start 0.7874 0.4064)
			(end 0.7874 -0.4064)
			(stroke
				(width 0.1524)
				(type default)
			)
			(layer "B.SilkS")
		)
		(fp_line
			(start -0.7874 -0.4064)
			(end -0.7874 0.4064)
			(stroke
				(width 0.1524)
				(type default)
			)
			(layer "B.SilkS")
		)
		(fp_line
			(start 0.7874 -0.4064)
			(end -0.7874 -0.4064)
			(stroke
				(width 0.1524)
				(type default)
			)
			(layer "B.SilkS")
		)
		(fp_line
			(start -0.67945 0.3048)
			(end -0.120396 0.3048)
			(stroke
				(width 0.1)
				(type default)
			)
			(layer "B.Fab")
		)
		(fp_line
			(start -0.120396 0.3048)
			(end -0.120396 0.2794)
			(stroke
				(width 0.1)
				(type default)
			)
			(layer "B.Fab")
		)
		(fp_line
			(start 0.12065 0.3048)
			(end 0.67945 0.3048)
			(stroke
				(width 0.1)
				(type default)
			)
			(layer "B.Fab")
		)
		(fp_line
			(start 0.67945 0.3048)
			(end 0.67945 -0.305054)
			(stroke
				(width 0.1)
				(type default)
			)
			(layer "B.Fab")
		)
		(fp_line
			(start -0.120396 0.2794)
			(end 0.12065 0.2794)
			(stroke
				(width 0.1)
				(type default)
			)
			(layer "B.Fab")
		)
		(fp_line
			(start 0.12065 0.2794)
			(end 0.12065 0.3048)
			(stroke
				(width 0.1)
				(type default)
			)
			(layer "B.Fab")
		)
		(fp_line
			(start -0.12065 -0.2794)
			(end -0.12065 -0.3048)
			(stroke
				(width 0.1)
				(type default)
			)
			(layer "B.Fab")
		)
		(fp_line
			(start 0.12065 -0.2794)
			(end -0.12065 -0.2794)
			(stroke
				(width 0.1)
				(type default)
			)
			(layer "B.Fab")
		)
		(fp_line
			(start -0.67945 -0.3048)
			(end -0.67945 0.3048)
			(stroke
				(width 0.1)
				(type default)
			)
			(layer "B.Fab")
		)
		(fp_line
			(start -0.12065 -0.3048)
			(end -0.67945 -0.3048)
			(stroke
				(width 0.1)
				(type default)
			)
			(layer "B.Fab")
		)
		(fp_line
			(start 0.12065 -0.305054)
			(end 0.12065 -0.2794)
			(stroke
				(width 0.1)
				(type default)
			)
			(layer "B.Fab")
		)
		(fp_line
			(start 0.67945 -0.305054)
			(end 0.12065 -0.305054)
			(stroke
				(width 0.1)
				(type default)
			)
			(layer "B.Fab")
		)
		(pad "1" smd circle
			(at 0.40005 0 90)
			(size 0 0)
			(layers "B.Cu" "B.Mask" "B.Paste")
			(net "P12V_E1S_ISET_0_R")
		)
		(pad "2" smd circle
			(at -0.40005 0 90)
			(size 0 0)
			(layers "B.Cu" "B.Mask" "B.Paste")
			(net "GND")
		)
	)
	(footprint ""
		(layer "B.Cu")
		(at 102.378764 -259.73024 180)
		(property "Reference" "C2102"
			(at 0 0 0)
			(layer "B.SilkS")
			(hide yes)
			(effects
				(font
					(size 1.27 1.27)
				)
				(justify mirror)
			)
		)
		(property "Value" ""
			(at 0 0 0)
			(layer "B.Fab")
			(effects
				(font
					(size 1.27 1.27)
				)
				(justify mirror)
			)
		)
		(duplicate_pad_numbers_are_jumpers no)
		(fp_line
			(start 0.7874 0.4064)
			(end 0.7874 -0.4064)
			(stroke
				(width 0.1524)
				(type default)
			)
			(layer "B.SilkS")
		)
		(fp_line
			(start 0.7874 -0.4064)
			(end -0.7874 -0.4064)
			(stroke
				(width 0.1524)
				(type default)
			)
			(layer "B.SilkS")
		)
		(fp_line
			(start -0.7874 0.4064)
			(end 0.7874 0.4064)
			(stroke
				(width 0.1524)
				(type default)
			)
			(layer "B.SilkS")
		)
		(fp_line
			(start -0.7874 -0.4064)
			(end -0.7874 0.4064)
			(stroke
				(width 0.1524)
				(type default)
			)
			(layer "B.SilkS")
		)
		(fp_line
			(start 0.67945 0.3048)
			(end 0.67945 -0.305054)
			(stroke
				(width 0.1)
				(type default)
			)
			(layer "B.Fab")
		)
		(fp_line
			(start 0.67945 -0.305054)
			(end 0.12065 -0.305054)
			(stroke
				(width 0.1)
				(type default)
			)
			(layer "B.Fab")
		)
		(fp_line
			(start 0.12065 0.3048)
			(end 0.67945 0.3048)
			(stroke
				(width 0.1)
				(type default)
			)
			(layer "B.Fab")
		)
		(fp_line
			(start 0.12065 0.2794)
			(end 0.12065 0.3048)
			(stroke
				(width 0.1)
				(type default)
			)
			(layer "B.Fab")
		)
		(fp_line
			(start 0.12065 -0.2794)
			(end -0.12065 -0.2794)
			(stroke
				(width 0.1)
				(type default)
			)
			(layer "B.Fab")
		)
		(fp_line
			(start 0.12065 -0.305054)
			(end 0.12065 -0.2794)
			(stroke
				(width 0.1)
				(type default)
			)
			(layer "B.Fab")
		)
		(fp_line
			(start -0.120396 0.3048)
			(end -0.120396 0.2794)
			(stroke
				(width 0.1)
				(type default)
			)
			(layer "B.Fab")
		)
		(fp_line
			(start -0.120396 0.2794)
			(end 0.12065 0.2794)
			(stroke
				(width 0.1)
				(type default)
			)
			(layer "B.Fab")
		)
		(fp_line
			(start -0.12065 -0.2794)
			(end -0.12065 -0.3048)
			(stroke
				(width 0.1)
				(type default)
			)
			(layer "B.Fab")
		)
		(fp_line
			(start -0.12065 -0.3048)
			(end -0.67945 -0.3048)
			(stroke
				(width 0.1)
				(type default)
			)
			(layer "B.Fab")
		)
		(fp_line
			(start -0.67945 0.3048)
			(end -0.120396 0.3048)
			(stroke
				(width 0.1)
				(type default)
			)
			(layer "B.Fab")
		)
		(fp_line
			(start -0.67945 -0.3048)
			(end -0.67945 0.3048)
			(stroke
				(width 0.1)
				(type default)
			)
			(layer "B.Fab")
		)
		(pad "1" smd circle
			(at 0.40005 0)
			(size 0 0)
			(layers "B.Cu" "B.Mask" "B.Paste")
			(net "PVDDIO_P1")
		)
		(pad "2" smd circle
			(at -0.40005 0)
			(size 0 0)
			(layers "B.Cu" "B.Mask" "B.Paste")
			(net "GND")
		)
	)
	(footprint ""
		(layer "B.Cu")
		(at 206.429356 -383.612136 180)
		(property "Reference" "PR2527"
			(at 0 0 0)
			(layer "B.SilkS")
			(hide yes)
			(effects
				(font
					(size 1.27 1.27)
				)
				(justify mirror)
			)
		)
		(property "Value" ""
			(at 0 0 0)
			(layer "B.Fab")
			(effects
				(font
					(size 1.27 1.27)
				)
				(justify mirror)
			)
		)
		(duplicate_pad_numbers_are_jumpers no)
		(fp_line
			(start 0.7874 0.4064)
			(end 0.7874 -0.4064)
			(stroke
				(width 0.1524)
				(type default)
			)
			(layer "B.SilkS")
		)
		(fp_line
			(start 0.7874 -0.4064)
			(end -0.7874 -0.4064)
			(stroke
				(width 0.1524)
				(type default)
			)
			(layer "B.SilkS")
		)
		(fp_line
			(start -0.7874 0.4064)
			(end 0.7874 0.4064)
			(stroke
				(width 0.1524)
				(type default)
			)
			(layer "B.SilkS")
		)
		(fp_line
			(start -0.7874 -0.4064)
			(end -0.7874 0.4064)
			(stroke
				(width 0.1524)
				(type default)
			)
			(layer "B.SilkS")
		)
		(fp_line
			(start 0.67945 0.3048)
			(end 0.67945 -0.305054)
			(stroke
				(width 0.1)
				(type default)
			)
			(layer "B.Fab")
		)
		(fp_line
			(start 0.67945 -0.305054)
			(end 0.12065 -0.305054)
			(stroke
				(width 0.1)
				(type default)
			)
			(layer "B.Fab")
		)
		(fp_line
			(start 0.12065 0.3048)
			(end 0.67945 0.3048)
			(stroke
				(width 0.1)
				(type default)
			)
			(layer "B.Fab")
		)
		(fp_line
			(start 0.12065 0.2794)
			(end 0.12065 0.3048)
			(stroke
				(width 0.1)
				(type default)
			)
			(layer "B.Fab")
		)
		(fp_line
			(start 0.12065 -0.2794)
			(end -0.12065 -0.2794)
			(stroke
				(width 0.1)
				(type default)
			)
			(layer "B.Fab")
		)
		(fp_line
			(start 0.12065 -0.305054)
			(end 0.12065 -0.2794)
			(stroke
				(width 0.1)
				(type default)
			)
			(layer "B.Fab")
		)
		(fp_line
			(start -0.120396 0.3048)
			(end -0.120396 0.2794)
			(stroke
				(width 0.1)
				(type default)
			)
			(layer "B.Fab")
		)
		(fp_line
			(start -0.120396 0.2794)
			(end 0.12065 0.2794)
			(stroke
				(width 0.1)
				(type default)
			)
			(layer "B.Fab")
		)
		(fp_line
			(start -0.12065 -0.2794)
			(end -0.12065 -0.3048)
			(stroke
				(width 0.1)
				(type default)
			)
			(layer "B.Fab")
		)
		(fp_line
			(start -0.12065 -0.3048)
			(end -0.67945 -0.3048)
			(stroke
				(width 0.1)
				(type default)
			)
			(layer "B.Fab")
		)
		(fp_line
			(start -0.67945 0.3048)
			(end -0.120396 0.3048)
			(stroke
				(width 0.1)
				(type default)
			)
			(layer "B.Fab")
		)
		(fp_line
			(start -0.67945 -0.3048)
			(end -0.67945 0.3048)
			(stroke
				(width 0.1)
				(type default)
			)
			(layer "B.Fab")
		)
		(pad "1" smd circle
			(at 0.40005 0)
			(size 0 0)
			(layers "B.Cu" "B.Mask" "B.Paste")
			(net "P12V_HSC_SENSE2_N")
		)
		(pad "2" smd circle
			(at -0.40005 0)
			(size 0 0)
			(layers "B.Cu" "B.Mask" "B.Paste")
			(net "P12V_HSC_SENSE2_R4_N")
		)
	)
)
